(kicad_pcb
	(version 20260206)
	(generator "pcbnew")
	(generator_version "10.0")
	(general
		(thickness 1.6)
		(legacy_teardrops no)
	)
	(paper "A4")
	(title_block
		(title "panther-plus-userver — 13130-1b_20150205.brd")
		(comment 1 "Honey Badger (Wiwynn) / footprints 1006-1013 of 1509")
	)
	(layers
		(0 "F.Cu" signal "TOP")
		(4 "In1.Cu" signal "L2")
		(6 "In2.Cu" signal "L3")
		(8 "In3.Cu" signal "L4")
		(10 "In4.Cu" signal "L5")
		(12 "In5.Cu" signal "L6")
		(14 "In6.Cu" signal "L7")
		(16 "In7.Cu" signal "L8")
		(18 "In8.Cu" signal "L9")
		(20 "In9.Cu" signal "L10")
		(22 "In10.Cu" signal "L11")
		(2 "B.Cu" signal "BOTTOM")
		(9 "F.Adhes" user "F.Adhesive")
		(11 "B.Adhes" user "B.Adhesive")
		(13 "F.Paste" user "Package Geometry/Pastemask Top")
		(15 "B.Paste" user "Package Geometry/Pastemask Bottom")
		(5 "F.SilkS" user "Ref Des/Silkscreen Top")
		(7 "B.SilkS" user "Ref Des/Silkscreen Bottom")
		(1 "F.Mask" user "Board Geometry/Soldermask Top")
		(3 "B.Mask" user "Board Geometry/Soldermask Bottom")
		(17 "Dwgs.User" user "User.Drawings")
		(19 "Cmts.User" user "User.Comments")
		(21 "Eco1.User" user "User.Eco1")
		(23 "Eco2.User" user "User.Eco2")
		(25 "Edge.Cuts" user "Board Geometry/Outline")
		(27 "Margin" user)
		(31 "F.CrtYd" user "Package Geometry/Place Bound Top")
		(29 "B.CrtYd" user "Package Geometry/Place Bound Bottom")
		(35 "F.Fab" user "Ref Des/Assembly Top")
		(33 "B.Fab" user "Ref Des/Assembly Bottom")
	)
	(footprint ""
		(layer "B.Cu")
		(at 104.902 -27.321002)
		(property "Reference" "C241"
			(at 0 0 0)
			(layer "B.SilkS")
			(hide yes)
			(effects
				(font
					(size 1.27 1.27)
				)
				(justify mirror)
			)
		)
		(property "Value" "SC1U10V2KX-1GP"
			(at -1.1811 -2.7051 0)
			(unlocked yes)
			(layer "B.Fab")
			(hide yes)
			(effects
				(font
					(size 1.016 1.016)
					(thickness 0.1524)
				)
				(justify mirror)
			)
		)
		(property "Device Type" "C402H22"
			(at -1.1811 -4.2291 0)
			(unlocked yes)
			(layer "B.Fab")
			(hide yes)
			(effects
				(font
					(size 1.016 1.016)
					(thickness 0.1524)
				)
				(justify mirror)
			)
		)
		(duplicate_pad_numbers_are_jumpers no)
		(fp_rect
			(start 0.381 0.7366)
			(end -0.381 -0.7366)
			(stroke
				(width 0)
				(type default)
			)
			(fill no)
			(layer "B.CrtYd")
		)
		(fp_rect
			(start 0.381 0.7366)
			(end -0.381 -0.7366)
			(stroke
				(width 0)
				(type default)
			)
			(fill no)
			(layer "B.Fab")
		)
		(pad "1" smd custom
			(at 0 -0.4572 180)
			(size 0.1143 0.1143)
			(layers "B.Cu" "B.Mask" "B.Paste")
			(net "PV_VDDR")
			(options
				(clearance outline)
				(anchor circle)
			)
			(primitives
				(gr_poly
					(pts
						(arc
							(start -0.254 0.1778)
							(mid -0.239121 0.213721)
							(end -0.2032 0.2286)
						)
						(arc
							(start 0.2032 0.2286)
							(mid 0.239121 0.213721)
							(end 0.254 0.1778)
						)
						(arc
							(start 0.254 -0.1778)
							(mid 0.239121 -0.213721)
							(end 0.2032 -0.2286)
						)
						(arc
							(start -0.2032 -0.2286)
							(mid -0.239121 -0.213721)
							(end -0.254 -0.1778)
						)
					)
					(width 0)
					(fill yes)
				)
			)
		)
		(pad "2" smd custom
			(at 0 0.4572 180)
			(size 0.1143 0.1143)
			(layers "B.Cu" "B.Mask" "B.Paste")
			(net "GND")
			(options
				(clearance outline)
				(anchor circle)
			)
			(primitives
				(gr_poly
					(pts
						(arc
							(start -0.254 0.1778)
							(mid -0.239121 0.213721)
							(end -0.2032 0.2286)
						)
						(arc
							(start 0.2032 0.2286)
							(mid 0.239121 0.213721)
							(end 0.254 0.1778)
						)
						(arc
							(start 0.254 -0.1778)
							(mid 0.239121 -0.213721)
							(end 0.2032 -0.2286)
						)
						(arc
							(start -0.2032 -0.2286)
							(mid -0.239121 -0.213721)
							(end -0.254 -0.1778)
						)
					)
					(width 0)
					(fill yes)
				)
			)
		)
	)
	(footprint ""
		(layer "B.Cu")
		(at 88.519 -24.765 -90)
		(property "Reference" "C259"
			(at 0 0 90)
			(layer "B.SilkS")
			(hide yes)
			(effects
				(font
					(size 1.27 1.27)
				)
				(justify mirror)
			)
		)
		(property "Value" "SC1U10V2KX-1GP"
			(at -1.1811 -2.7051 270)
			(unlocked yes)
			(layer "B.Fab")
			(hide yes)
			(effects
				(font
					(size 1.016 1.016)
					(thickness 0.1524)
				)
				(justify mirror)
			)
		)
		(property "Device Type" "C402H22"
			(at -1.1811 -4.2291 270)
			(unlocked yes)
			(layer "B.Fab")
			(hide yes)
			(effects
				(font
					(size 1.016 1.016)
					(thickness 0.1524)
				)
				(justify mirror)
			)
		)
		(duplicate_pad_numbers_are_jumpers no)
		(fp_rect
			(start 0.381 0.7366)
			(end -0.381 -0.7366)
			(stroke
				(width 0)
				(type default)
			)
			(fill no)
			(layer "B.CrtYd")
		)
		(fp_rect
			(start 0.381 0.7366)
			(end -0.381 -0.7366)
			(stroke
				(width 0)
				(type default)
			)
			(fill no)
			(layer "B.Fab")
		)
		(pad "1" smd custom
			(at 0 -0.4572 90)
			(size 0.1143 0.1143)
			(layers "B.Cu" "B.Mask" "B.Paste")
			(net "P1V0")
			(options
				(clearance outline)
				(anchor circle)
			)
			(primitives
				(gr_poly
					(pts
						(arc
							(start -0.254 0.1778)
							(mid -0.239121 0.213721)
							(end -0.2032 0.2286)
						)
						(arc
							(start 0.2032 0.2286)
							(mid 0.239121 0.213721)
							(end 0.254 0.1778)
						)
						(arc
							(start 0.254 -0.1778)
							(mid 0.239121 -0.213721)
							(end 0.2032 -0.2286)
						)
						(arc
							(start -0.2032 -0.2286)
							(mid -0.239121 -0.213721)
							(end -0.254 -0.1778)
						)
					)
					(width 0)
					(fill yes)
				)
			)
		)
		(pad "2" smd custom
			(at 0 0.4572 90)
			(size 0.1143 0.1143)
			(layers "B.Cu" "B.Mask" "B.Paste")
			(net "GND")
			(options
				(clearance outline)
				(anchor circle)
			)
			(primitives
				(gr_poly
					(pts
						(arc
							(start -0.254 0.1778)
							(mid -0.239121 0.213721)
							(end -0.2032 0.2286)
						)
						(arc
							(start 0.2032 0.2286)
							(mid 0.239121 0.213721)
							(end 0.254 0.1778)
						)
						(arc
							(start 0.254 -0.1778)
							(mid 0.239121 -0.213721)
							(end 0.2032 -0.2286)
						)
						(arc
							(start -0.2032 -0.2286)
							(mid -0.239121 -0.213721)
							(end -0.254 -0.1778)
						)
					)
					(width 0)
					(fill yes)
				)
			)
		)
	)
	(footprint ""
		(layer "B.Cu")
		(at 189.5856 -12.701778 90)
		(property "Reference" "R198"
			(at 0 0 90)
			(layer "B.SilkS")
			(hide yes)
			(effects
				(font
					(size 1.27 1.27)
				)
				(justify mirror)
			)
		)
		(property "Value" "4K7R2F-GP"
			(at -0.064008 -3.993896 90)
			(unlocked yes)
			(layer "B.Fab")
			(hide yes)
			(effects
				(font
					(size 1.016 1.016)
					(thickness 0.1524)
				)
				(justify mirror)
			)
		)
		(property "Device Type" "R402H16"
			(at -0.064008 -5.517896 90)
			(unlocked yes)
			(layer "B.Fab")
			(hide yes)
			(effects
				(font
					(size 1.016 1.016)
					(thickness 0.1524)
				)
				(justify mirror)
			)
		)
		(duplicate_pad_numbers_are_jumpers no)
		(fp_rect
			(start 0.381 0.8382)
			(end -0.381 -0.8382)
			(stroke
				(width 0)
				(type default)
			)
			(fill no)
			(layer "B.CrtYd")
		)
		(fp_rect
			(start 0.381 0.8382)
			(end -0.381 -0.8382)
			(stroke
				(width 0)
				(type default)
			)
			(fill no)
			(layer "B.Fab")
		)
		(pad "1" smd custom
			(at 0 -0.4318 270)
			(size 0.127 0.127)
			(layers "B.Cu" "B.Mask" "B.Paste")
			(net "P3V3_STBY")
			(options
				(clearance outline)
				(anchor circle)
			)
			(primitives
				(gr_poly
					(pts
						(arc
							(start -0.2032 0.2794)
							(mid -0.239121 0.264521)
							(end -0.254 0.2286)
						)
						(arc
							(start -0.254 -0.2286)
							(mid -0.239121 -0.264521)
							(end -0.2032 -0.2794)
						)
						(arc
							(start 0.2032 -0.2794)
							(mid 0.239121 -0.264521)
							(end 0.254 -0.2286)
						)
						(arc
							(start 0.254 0.2286)
							(mid 0.239121 0.264521)
							(end 0.2032 0.2794)
						)
					)
					(width 0)
					(fill yes)
				)
			)
		)
		(pad "2" smd custom
			(at 0 0.4318 270)
			(size 0.127 0.127)
			(layers "B.Cu" "B.Mask" "B.Paste")
			(net "CHB_0_SA1")
			(options
				(clearance outline)
				(anchor circle)
			)
			(primitives
				(gr_poly
					(pts
						(arc
							(start -0.2032 0.2794)
							(mid -0.239121 0.264521)
							(end -0.254 0.2286)
						)
						(arc
							(start -0.254 -0.2286)
							(mid -0.239121 -0.264521)
							(end -0.2032 -0.2794)
						)
						(arc
							(start 0.2032 -0.2794)
							(mid 0.239121 -0.264521)
							(end 0.254 -0.2286)
						)
						(arc
							(start 0.254 0.2286)
							(mid 0.239121 0.264521)
							(end 0.2032 0.2794)
						)
					)
					(width 0)
					(fill yes)
				)
			)
		)
	)
	(footprint ""
		(layer "B.Cu")
		(at 117.0432 -36.5506 90)
		(property "Reference" "PTC4"
			(at 0 0 90)
			(layer "B.SilkS")
			(hide yes)
			(effects
				(font
					(size 1.27 1.27)
				)
				(justify mirror)
			)
		)
		(property "Value" "SE470UF2VDM-GP"
			(at 0 -9.6012 90)
			(unlocked yes)
			(layer "B.Fab")
			(hide yes)
			(effects
				(font
					(size 1.016 1.016)
					(thickness 0.1524)
				)
				(justify mirror)
			)
		)
		(property "Device Type" "CT7343H83"
			(at 0 -11.1252 90)
			(unlocked yes)
			(layer "B.Fab")
			(hide yes)
			(effects
				(font
					(size 1.016 1.016)
					(thickness 0.1524)
				)
				(justify mirror)
			)
		)
		(duplicate_pad_numbers_are_jumpers no)
		(fp_line
			(start 2.206752 -4.2926)
			(end -2.155698 -4.2926)
			(stroke
				(width 0.508)
				(type default)
			)
			(layer "B.SilkS")
		)
		(fp_rect
			(start 2.1463 3.6449)
			(end -2.1463 -3.6449)
			(stroke
				(width 0)
				(type default)
			)
			(fill no)
			(layer "B.CrtYd")
		)
		(fp_poly
			(pts
				(xy 3.81 3.9116) (xy 3.81 -3.9116) (xy 2.54 -3.9116) (xy 2.4003 -3.9116) (xy 2.4003 -4.0386) (xy -2.4003 -4.0386)
				(xy -2.4003 -3.9116) (xy -2.54 -3.9116) (xy -2.5654 -3.9116) (xy -3.81 -3.9116) (xy -3.81 -1.6256)
				(xy -2.1463 -1.6256) (xy -2.1463 -3.6449) (xy 2.1463 -3.6449) (xy 2.1463 3.6449) (xy -2.1463 3.6449)
				(xy -2.1463 -1.6129) (xy -3.81 -1.6129) (xy -3.81 3.9116) (xy -2.4003 3.9116) (xy -2.4003 3.9243)
				(xy -2.4003 4.0386) (xy 2.4003 4.0386) (xy 2.4003 3.9116)
			)
			(stroke
				(width 0)
				(type default)
			)
			(fill no)
			(layer "B.CrtYd")
		)
		(fp_rect
			(start 3.81 3.9116)
			(end 2.4003 -3.9116)
			(stroke
				(width 0)
				(type default)
			)
			(fill no)
			(layer "B.Fab")
		)
		(fp_rect
			(start -2.4003 3.9116)
			(end -3.81 -3.9116)
			(stroke
				(width 0)
				(type default)
			)
			(fill no)
			(layer "B.Fab")
		)
		(fp_rect
			(start 2.4003 4.0386)
			(end -2.4003 -4.0386)
			(stroke
				(width 0)
				(type default)
			)
			(fill no)
			(layer "B.Fab")
		)
		(pad "1" smd rect
			(at 0 -2.9591 270)
			(size 2.413 1.905)
			(layers "B.Cu" "B.Mask" "B.Paste")
			(net "PVCCP")
		)
		(pad "2" smd rect
			(at 0 2.9591 270)
			(size 2.413 1.905)
			(layers "B.Cu" "B.Mask" "B.Paste")
			(net "GND")
		)
	)
	(footprint ""
		(layer "B.Cu")
		(at 33.147 -42.926 90)
		(property "Reference" "PR186"
			(at 0 0 90)
			(layer "B.SilkS")
			(hide yes)
			(effects
				(font
					(size 1.27 1.27)
				)
				(justify mirror)
			)
		)
		(property "Value" "4K22R2F-GP"
			(at -1.7907 -1.1176 90)
			(unlocked yes)
			(layer "B.Fab")
			(hide yes)
			(effects
				(font
					(size 1.016 1.016)
					(thickness 0.1524)
				)
				(justify mirror)
			)
		)
		(property "Device Type" "R402H16"
			(at -1.7907 -2.6416 90)
			(unlocked yes)
			(layer "B.Fab")
			(hide yes)
			(effects
				(font
					(size 1.016 1.016)
					(thickness 0.1524)
				)
				(justify mirror)
			)
		)
		(duplicate_pad_numbers_are_jumpers no)
		(fp_rect
			(start 0.381 0.8382)
			(end -0.381 -0.8382)
			(stroke
				(width 0)
				(type default)
			)
			(fill no)
			(layer "B.CrtYd")
		)
		(fp_rect
			(start 0.381 0.8382)
			(end -0.381 -0.8382)
			(stroke
				(width 0)
				(type default)
			)
			(fill no)
			(layer "B.Fab")
		)
		(pad "1" smd custom
			(at 0 -0.4318 270)
			(size 0.127 0.127)
			(layers "B.Cu" "B.Mask" "B.Paste")
			(net "P1V5_STBY_OUT")
			(options
				(clearance outline)
				(anchor circle)
			)
			(primitives
				(gr_poly
					(pts
						(arc
							(start -0.2032 0.2794)
							(mid -0.239121 0.264521)
							(end -0.254 0.2286)
						)
						(arc
							(start -0.254 -0.2286)
							(mid -0.239121 -0.264521)
							(end -0.2032 -0.2794)
						)
						(arc
							(start 0.2032 -0.2794)
							(mid 0.239121 -0.264521)
							(end 0.254 -0.2286)
						)
						(arc
							(start 0.254 0.2286)
							(mid 0.239121 0.264521)
							(end 0.2032 0.2794)
						)
					)
					(width 0)
					(fill yes)
				)
			)
		)
		(pad "2" smd custom
			(at 0 0.4318 270)
			(size 0.127 0.127)
			(layers "B.Cu" "B.Mask" "B.Paste")
			(net "P1V5_STBY_FB")
			(options
				(clearance outline)
				(anchor circle)
			)
			(primitives
				(gr_poly
					(pts
						(arc
							(start -0.2032 0.2794)
							(mid -0.239121 0.264521)
							(end -0.254 0.2286)
						)
						(arc
							(start -0.254 -0.2286)
							(mid -0.239121 -0.264521)
							(end -0.2032 -0.2794)
						)
						(arc
							(start 0.2032 -0.2794)
							(mid 0.239121 -0.264521)
							(end 0.254 -0.2286)
						)
						(arc
							(start 0.254 0.2286)
							(mid 0.239121 0.264521)
							(end 0.2032 0.2794)
						)
					)
					(width 0)
					(fill yes)
				)
			)
		)
	)
	(footprint ""
		(layer "B.Cu")
		(at 22.352 -64.77 180)
		(property "Reference" "PR26"
			(at 0 0 0)
			(layer "B.SilkS")
			(hide yes)
			(effects
				(font
					(size 1.27 1.27)
				)
				(justify mirror)
			)
		)
		(property "Value" "13K7R2F-GP"
			(at -1.7907 -1.1176 180)
			(unlocked yes)
			(layer "B.Fab")
			(hide yes)
			(effects
				(font
					(size 1.016 1.016)
					(thickness 0.1524)
				)
				(justify mirror)
			)
		)
		(property "Device Type" "R402H16"
			(at -1.7907 -2.6416 180)
			(unlocked yes)
			(layer "B.Fab")
			(hide yes)
			(effects
				(font
					(size 1.016 1.016)
					(thickness 0.1524)
				)
				(justify mirror)
			)
		)
		(duplicate_pad_numbers_are_jumpers no)
		(fp_rect
			(start 0.381 0.8382)
			(end -0.381 -0.8382)
			(stroke
				(width 0)
				(type default)
			)
			(fill no)
			(layer "B.CrtYd")
		)
		(fp_rect
			(start 0.381 0.8382)
			(end -0.381 -0.8382)
			(stroke
				(width 0)
				(type default)
			)
			(fill no)
			(layer "B.Fab")
		)
		(pad "1" smd custom
			(at 0 -0.4318)
			(size 0.127 0.127)
			(layers "B.Cu" "B.Mask" "B.Paste")
			(net "VR_PVNN_PROG2")
			(options
				(clearance outline)
				(anchor circle)
			)
			(primitives
				(gr_poly
					(pts
						(arc
							(start -0.2032 0.2794)
							(mid -0.239121 0.264521)
							(end -0.254 0.2286)
						)
						(arc
							(start -0.254 -0.2286)
							(mid -0.239121 -0.264521)
							(end -0.2032 -0.2794)
						)
						(arc
							(start 0.2032 -0.2794)
							(mid 0.239121 -0.264521)
							(end 0.254 -0.2286)
						)
						(arc
							(start 0.254 0.2286)
							(mid 0.239121 0.264521)
							(end 0.2032 0.2794)
						)
					)
					(width 0)
					(fill yes)
				)
			)
		)
		(pad "2" smd custom
			(at 0 0.4318)
			(size 0.127 0.127)
			(layers "B.Cu" "B.Mask" "B.Paste")
			(net "GND")
			(options
				(clearance outline)
				(anchor circle)
			)
			(primitives
				(gr_poly
					(pts
						(arc
							(start -0.2032 0.2794)
							(mid -0.239121 0.264521)
							(end -0.254 0.2286)
						)
						(arc
							(start -0.254 -0.2286)
							(mid -0.239121 -0.264521)
							(end -0.2032 -0.2794)
						)
						(arc
							(start 0.2032 -0.2794)
							(mid 0.239121 -0.264521)
							(end 0.254 -0.2286)
						)
						(arc
							(start 0.254 0.2286)
							(mid 0.239121 0.264521)
							(end 0.2032 0.2794)
						)
					)
					(width 0)
					(fill yes)
				)
			)
		)
	)
	(footprint ""
		(layer "B.Cu")
		(at 84.65058 -35.87496)
		(property "Reference" "TP60"
			(at 0 0 0)
			(layer "B.SilkS")
			(hide yes)
			(effects
				(font
					(size 1.27 1.27)
				)
				(justify mirror)
			)
		)
		(property "Value" "TPAD32-GP"
			(at 0 -3.166364 0)
			(unlocked yes)
			(layer "B.Fab")
			(hide yes)
			(effects
				(font
					(size 1.016 1.016)
					(thickness 0.1524)
				)
				(justify mirror)
			)
		)
		(property "Device Type" "TPAD32"
			(at 0 -4.690618 0)
			(unlocked yes)
			(layer "B.Fab")
			(hide yes)
			(effects
				(font
					(size 1.016 1.016)
					(thickness 0.1524)
				)
				(justify mirror)
			)
		)
		(duplicate_pad_numbers_are_jumpers no)
		(fp_poly
			(pts
				(arc
					(start 0.7112 0)
					(mid -0.7112 0)
					(end 0.7112 0)
				)
			)
			(stroke
				(width 0)
				(type default)
			)
			(fill no)
			(layer "B.CrtYd")
		)
		(fp_poly
			(pts
				(arc
					(start 0.7112 0)
					(mid -0.7112 0)
					(end 0.7112 0)
				)
			)
			(stroke
				(width 0)
				(type default)
			)
			(fill no)
			(layer "B.Fab")
		)
		(pad "1" smd circle
			(at 0 0 180)
			(size 0.8128 0.8128)
			(layers "B.Cu" "B.Mask" "B.Paste")
			(net "XDP_SOC_CPU_TDI")
		)
	)
	(footprint ""
		(layer "B.Cu")
		(at 201.2442 -49.7332 90)
		(property "Reference" "PTC2"
			(at 0 0 90)
			(layer "B.SilkS")
			(hide yes)
			(effects
				(font
					(size 1.27 1.27)
				)
				(justify mirror)
			)
		)
		(property "Value" "SE470UF2VDM-GP"
			(at 3.220466 1.242822 90)
			(unlocked yes)
			(layer "B.Fab")
			(hide yes)
			(effects
				(font
					(size 1.016 1.016)
					(thickness 0.1524)
				)
				(justify mirror)
			)
		)
		(property "Device Type" "CT7343H83"
			(at 3.220466 -0.281178 90)
			(unlocked yes)
			(layer "B.Fab")
			(hide yes)
			(effects
				(font
					(size 1.016 1.016)
					(thickness 0.1524)
				)
				(justify mirror)
			)
		)
		(duplicate_pad_numbers_are_jumpers no)
		(fp_line
			(start 2.206752 -4.2926)
			(end -2.155698 -4.2926)
			(stroke
				(width 0.508)
				(type default)
			)
			(layer "B.SilkS")
		)
		(fp_rect
			(start 2.1463 3.6449)
			(end -2.1463 -3.6449)
			(stroke
				(width 0)
				(type default)
			)
			(fill no)
			(layer "B.CrtYd")
		)
		(fp_poly
			(pts
				(xy 3.81 3.9116) (xy 3.81 -3.9116) (xy 2.54 -3.9116) (xy 2.4003 -3.9116) (xy 2.4003 -4.0386) (xy -2.4003 -4.0386)
				(xy -2.4003 -3.9116) (xy -2.54 -3.9116) (xy -2.5654 -3.9116) (xy -3.81 -3.9116) (xy -3.81 -1.6256)
				(xy -2.1463 -1.6256) (xy -2.1463 -3.6449) (xy 2.1463 -3.6449) (xy 2.1463 3.6449) (xy -2.1463 3.6449)
				(xy -2.1463 -1.6129) (xy -3.81 -1.6129) (xy -3.81 3.9116) (xy -2.4003 3.9116) (xy -2.4003 3.9243)
				(xy -2.4003 4.0386) (xy 2.4003 4.0386) (xy 2.4003 3.9116)
			)
			(stroke
				(width 0)
				(type default)
			)
			(fill no)
			(layer "B.CrtYd")
		)
		(fp_rect
			(start 3.81 3.9116)
			(end 2.4003 -3.9116)
			(stroke
				(width 0)
				(type default)
			)
			(fill no)
			(layer "B.Fab")
		)
		(fp_rect
			(start -2.4003 3.9116)
			(end -3.81 -3.9116)
			(stroke
				(width 0)
				(type default)
			)
			(fill no)
			(layer "B.Fab")
		)
		(fp_rect
			(start 2.4003 4.0386)
			(end -2.4003 -4.0386)
			(stroke
				(width 0)
				(type default)
			)
			(fill no)
			(layer "B.Fab")
		)
		(pad "1" smd rect
			(at 0 -2.9591 270)
			(size 2.413 1.905)
			(layers "B.Cu" "B.Mask" "B.Paste")
			(net "PV_VDDR")
		)
		(pad "2" smd rect
			(at 0 2.9591 270)
			(size 2.413 1.905)
			(layers "B.Cu" "B.Mask" "B.Paste")
			(net "GND")
		)
	)
)
